(kicad_pcb
	(version 20241229)
	(generator "pcbnew")
	(generator_version "9.0")
	(general
		(thickness 1.62)
		(legacy_teardrops no)
	)
	(paper "A3")
	(title_block
		(title "COM Express 7 Baseboard")
		(date "2025-02-04")
		(rev "1.1.2")
		(company "Antmicro Ltd")
		(comment 1 "www.antmicro.com")
		(comment 9 "footprint 386 of 802 (J1), pads 1-38 of 38")
	)
	(layers
		(0 "F.Cu" signal)
		(4 "In1.Cu" signal)
		(6 "In2.Cu" signal)
		(8 "In3.Cu" signal)
		(10 "In4.Cu" signal)
		(12 "In5.Cu" signal)
		(14 "In6.Cu" signal)
		(2 "B.Cu" signal)
		(9 "F.Adhes" user "F.Adhesive")
		(11 "B.Adhes" user "B.Adhesive")
		(13 "F.Paste" user)
		(15 "B.Paste" user)
		(5 "F.SilkS" user "F.Silkscreen")
		(7 "B.SilkS" user "B.Silkscreen")
		(1 "F.Mask" user)
		(3 "B.Mask" user)
		(17 "Dwgs.User" user "User.Drawings")
		(19 "Cmts.User" user "User.Comments")
		(21 "Eco1.User" user "User.Eco1")
		(23 "Eco2.User" user "User.Eco2")
		(25 "Edge.Cuts" user)
		(27 "Margin" user)
		(31 "F.CrtYd" user "F.Courtyard")
		(29 "B.CrtYd" user "B.Courtyard")
		(35 "F.Fab" user)
		(33 "B.Fab" user)
	)
	(footprint "antmicro-footprints:RJ45_RJE361882415"
		(layer "F.Cu")
		(at 118.15 109.81 -90)
		(property "Reference" "J1"
			(at 6.2 22.55 0)
			(unlocked yes)
			(layer "F.SilkS")
			(effects
				(font
					(size 0.7 0.7)
					(thickness 0.15)
				)
				(justify left bottom)
			)
		)
		(property "Value" "Amphenol_RJE361882415"
			(at 3.555 23.9 270)
			(unlocked yes)
			(layer "F.Fab")
			(effects
				(font
					(size 0.7 0.7)
					(thickness 0.15)
				)
				(justify left bottom)
			)
		)
		(property "Datasheet" "https://cdn.amphenol-cs.com/media/wysiwyg/files/drawing/p-rje36-188-2xx5.pdf"
			(at 0 0 270)
			(layer "F.Fab")
			(hide yes)
			(effects
				(font
					(size 1.27 1.27)
					(thickness 0.15)
				)
			)
		)
		(property "Description" "Modular Connectors / Ethernet Connectors MODULAR JACK"
			(at 0 0 270)
			(layer "F.Fab")
			(hide yes)
			(effects
				(font
					(size 1.27 1.27)
					(thickness 0.15)
				)
			)
		)
		(property "Author" "Antmicro"
			(at 8.34 227.96 0)
			(layer "F.Fab")
			(hide yes)
			(effects
				(font
					(size 1 1)
					(thickness 0.15)
				)
			)
		)
		(property "License" "Apache-2.0"
			(at 8.34 227.96 0)
			(layer "F.Fab")
			(hide yes)
			(effects
				(font
					(size 1 1)
					(thickness 0.15)
				)
			)
		)
		(property "MPN" "RJE361882415"
			(at 8.34 227.96 0)
			(layer "F.Fab")
			(hide yes)
			(effects
				(font
					(size 1 1)
					(thickness 0.15)
				)
			)
		)
		(property "Manufacturer" "Amphenol"
			(at 8.34 227.96 0)
			(layer "F.Fab")
			(hide yes)
			(effects
				(font
					(size 1 1)
					(thickness 0.15)
				)
			)
		)
		(sheetname "2xUSB3.0+RJ45")
		(sheetfile "usb3+rj45.kicad_sch")
		(attr through_hole)
		(pad "1" thru_hole circle
			(at 0 0)
			(size 1.35 1.35)
			(drill 1)
			(layers "*.Cu" "*.Mask")
			(remove_unused_layers no)
			(net 146 "/2xUSB3.0+RJ45/DA+")
			(pinfunction "1")
			(pintype "bidirectional")
			(teardrops
				(best_length_ratio 0.4)
				(max_length 1)
				(best_width_ratio 0.9)
				(max_width 2)
				(curved_edges yes)
				(filter_ratio 0.9)
				(enabled yes)
				(allow_two_segments yes)
				(prefer_zone_connections yes)
			)
		)
		(pad "2" thru_hole circle
			(at -1.27 2.54)
			(size 1.35 1.35)
			(drill 1)
			(layers "*.Cu" "*.Mask")
			(remove_unused_layers no)
			(net 147 "/2xUSB3.0+RJ45/DA-")
			(pinfunction "2")
			(pintype "bidirectional")
			(teardrops
				(best_length_ratio 0.4)
				(max_length 1)
				(best_width_ratio 0.9)
				(max_width 2)
				(curved_edges yes)
				(filter_ratio 0.9)
				(enabled yes)
				(allow_two_segments yes)
				(prefer_zone_connections yes)
			)
		)
		(pad "3" thru_hole circle
			(at -2.54 0)
			(size 1.35 1.35)
			(drill 1)
			(layers "*.Cu" "*.Mask")
			(remove_unused_layers no)
			(net 148 "/2xUSB3.0+RJ45/DB+")
			(pinfunction "3")
			(pintype "bidirectional")
			(teardrops
				(best_length_ratio 0.4)
				(max_length 1)
				(best_width_ratio 0.9)
				(max_width 2)
				(curved_edges yes)
				(filter_ratio 0.9)
				(enabled yes)
				(allow_two_segments yes)
				(prefer_zone_connections yes)
			)
		)
		(pad "4" thru_hole circle
			(at -3.81 2.54)
			(size 1.35 1.35)
			(drill 1)
			(layers "*.Cu" "*.Mask")
			(remove_unused_layers no)
			(net 149 "/2xUSB3.0+RJ45/DC+")
			(pinfunction "4")
			(pintype "bidirectional")
			(teardrops
				(best_length_ratio 0.4)
				(max_length 1)
				(best_width_ratio 0.9)
				(max_width 2)
				(curved_edges yes)
				(filter_ratio 0.9)
				(enabled yes)
				(allow_two_segments yes)
				(prefer_zone_connections yes)
			)
		)
		(pad "5" thru_hole circle
			(at -5.08 0)
			(size 1.35 1.35)
			(drill 1)
			(layers "*.Cu" "*.Mask")
			(remove_unused_layers no)
			(net 150 "/2xUSB3.0+RJ45/DC-")
			(pinfunction "5")
			(pintype "bidirectional")
			(teardrops
				(best_length_ratio 0.4)
				(max_length 1)
				(best_width_ratio 0.9)
				(max_width 2)
				(curved_edges yes)
				(filter_ratio 0.9)
				(enabled yes)
				(allow_two_segments yes)
				(prefer_zone_connections yes)
			)
		)
		(pad "6" thru_hole circle
			(at -6.35 2.54)
			(size 1.35 1.35)
			(drill 1)
			(layers "*.Cu" "*.Mask")
			(remove_unused_layers no)
			(net 151 "/2xUSB3.0+RJ45/DB-")
			(pinfunction "6")
			(pintype "bidirectional")
			(teardrops
				(best_length_ratio 0.4)
				(max_length 1)
				(best_width_ratio 0.9)
				(max_width 2)
				(curved_edges yes)
				(filter_ratio 0.9)
				(enabled yes)
				(allow_two_segments yes)
				(prefer_zone_connections yes)
			)
		)
		(pad "7" thru_hole circle
			(at -7.62 0)
			(size 1.35 1.35)
			(drill 1)
			(layers "*.Cu" "*.Mask")
			(remove_unused_layers no)
			(net 152 "/2xUSB3.0+RJ45/DD+")
			(pinfunction "7")
			(pintype "bidirectional")
			(teardrops
				(best_length_ratio 0.4)
				(max_length 1)
				(best_width_ratio 0.9)
				(max_width 2)
				(curved_edges yes)
				(filter_ratio 0.9)
				(enabled yes)
				(allow_two_segments yes)
				(prefer_zone_connections yes)
			)
		)
		(pad "8" thru_hole circle
			(at -8.89 2.54)
			(size 1.35 1.35)
			(drill 1)
			(layers "*.Cu" "*.Mask")
			(remove_unused_layers no)
			(net 153 "/2xUSB3.0+RJ45/DD-")
			(pinfunction "8")
			(pintype "bidirectional")
			(teardrops
				(best_length_ratio 0.4)
				(max_length 1)
				(best_width_ratio 0.9)
				(max_width 2)
				(curved_edges yes)
				(filter_ratio 0.9)
				(enabled yes)
				(allow_two_segments yes)
				(prefer_zone_connections yes)
			)
		)
		(pad "D1" thru_hole circle
			(at -11.645 -2.71)
			(size 1.35 1.35)
			(drill 1)
			(layers "*.Cu" "*.Mask")
			(remove_unused_layers no)
			(net 154 "Net-(J1A-LED_D1)")
			(pinfunction "LED_D1")
			(pintype "passive")
			(teardrops
				(best_length_ratio 0.4)
				(max_length 1)
				(best_width_ratio 0.9)
				(max_width 2)
				(curved_edges yes)
				(filter_ratio 0.9)
				(enabled yes)
				(allow_two_segments yes)
				(prefer_zone_connections yes)
			)
		)
		(pad "D2" thru_hole circle
			(at -9.11 -2.71)
			(size 1.35 1.35)
			(drill 1)
			(layers "*.Cu" "*.Mask")
			(remove_unused_layers no)
			(net 155 "Net-(J1A-LED_D2)")
			(pinfunction "LED_D2")
			(pintype "passive")
			(teardrops
				(best_length_ratio 0.4)
				(max_length 1)
				(best_width_ratio 0.9)
				(max_width 2)
				(curved_edges yes)
				(filter_ratio 0.9)
				(enabled yes)
				(allow_two_segments yes)
				(prefer_zone_connections yes)
			)
		)
		(pad "D3" thru_hole circle
			(at 0.22 -2.71)
			(size 1.35 1.35)
			(drill 1)
			(layers "*.Cu" "*.Mask")
			(remove_unused_layers no)
			(net 156 "Net-(J1A-LED_D3)")
			(pinfunction "LED_D3")
			(pintype "passive")
			(teardrops
				(best_length_ratio 0.4)
				(max_length 1)
				(best_width_ratio 0.9)
				(max_width 2)
				(curved_edges yes)
				(filter_ratio 0.9)
				(enabled yes)
				(allow_two_segments yes)
				(prefer_zone_connections yes)
			)
		)
		(pad "D4" thru_hole circle
			(at 2.755 -2.71)
			(size 1.35 1.35)
			(drill 1)
			(layers "*.Cu" "*.Mask")
			(remove_unused_layers no)
			(net 157 "Net-(J1A-LED_D4)")
			(pinfunction "LED_D4")
			(pintype "passive")
			(teardrops
				(best_length_ratio 0.4)
				(max_length 1)
				(best_width_ratio 0.9)
				(max_width 2)
				(curved_edges yes)
				(filter_ratio 0.9)
				(enabled yes)
				(allow_two_segments yes)
				(prefer_zone_connections yes)
			)
		)
		(pad "MP" thru_hole circle
			(at -13.77 2.49)
			(size 3 3)
			(drill 2.3)
			(layers "*.Cu" "*.Mask")
			(remove_unused_layers no)
			(net 579 "/2xUSB3.0+RJ45/SH")
			(pinfunction "MP")
			(pintype "bidirectional")
			(teardrops
				(best_length_ratio 0.4)
				(max_length 1)
				(best_width_ratio 0.9)
				(max_width 2)
				(curved_edges yes)
				(filter_ratio 0.9)
				(enabled yes)
				(allow_two_segments yes)
				(prefer_zone_connections yes)
			)
		)
		(pad "MP" thru_hole circle
			(at -13.77 15.09)
			(size 3 3)
			(drill 2.3)
			(layers "*.Cu" "*.Mask")
			(remove_unused_layers no)
			(net 579 "/2xUSB3.0+RJ45/SH")
			(pinfunction "MP")
			(pintype "bidirectional")
			(teardrops
				(best_length_ratio 0.4)
				(max_length 1)
				(best_width_ratio 0.9)
				(max_width 2)
				(curved_edges yes)
				(filter_ratio 0.9)
				(enabled yes)
				(allow_two_segments yes)
				(prefer_zone_connections yes)
			)
		)
		(pad "MP" thru_hole circle
			(at -11.015 7.71)
			(size 3 3)
			(drill 2.3)
			(layers "*.Cu" "*.Mask")
			(remove_unused_layers no)
			(net 579 "/2xUSB3.0+RJ45/SH")
			(pinfunction "MP")
			(pintype "bidirectional")
			(teardrops
				(best_length_ratio 0.4)
				(max_length 1)
				(best_width_ratio 0.9)
				(max_width 2)
				(curved_edges yes)
				(filter_ratio 0.9)
				(enabled yes)
				(allow_two_segments yes)
				(prefer_zone_connections yes)
			)
		)
		(pad "MP" thru_hole circle
			(at -11.015 13.39)
			(size 3 3)
			(drill 2.3)
			(layers "*.Cu" "*.Mask")
			(remove_unused_layers no)
			(net 579 "/2xUSB3.0+RJ45/SH")
			(pinfunction "MP")
			(pintype "bidirectional")
			(teardrops
				(best_length_ratio 0.4)
				(max_length 1)
				(best_width_ratio 0.9)
				(max_width 2)
				(curved_edges yes)
				(filter_ratio 0.9)
				(enabled yes)
				(allow_two_segments yes)
				(prefer_zone_connections yes)
			)
		)
		(pad "MP" thru_hole circle
			(at 2.125 7.71)
			(size 3 3)
			(drill 2.3)
			(layers "*.Cu" "*.Mask")
			(remove_unused_layers no)
			(net 579 "/2xUSB3.0+RJ45/SH")
			(pinfunction "MP")
			(pintype "bidirectional")
			(teardrops
				(best_length_ratio 0.4)
				(max_length 1)
				(best_width_ratio 0.9)
				(max_width 2)
				(curved_edges yes)
				(filter_ratio 0.9)
				(enabled yes)
				(allow_two_segments yes)
				(prefer_zone_connections yes)
			)
		)
		(pad "MP" thru_hole circle
			(at 2.125 13.39)
			(size 3 3)
			(drill 2.3)
			(layers "*.Cu" "*.Mask")
			(remove_unused_layers no)
			(net 579 "/2xUSB3.0+RJ45/SH")
			(pinfunction "MP")
			(pintype "bidirectional")
			(teardrops
				(best_length_ratio 0.4)
				(max_length 1)
				(best_width_ratio 0.9)
				(max_width 2)
				(curved_edges yes)
				(filter_ratio 0.9)
				(enabled yes)
				(allow_two_segments yes)
				(prefer_zone_connections yes)
			)
		)
		(pad "MP" thru_hole circle
			(at 4.88 2.49)
			(size 3 3)
			(drill 2.3)
			(layers "*.Cu" "*.Mask")
			(remove_unused_layers no)
			(net 579 "/2xUSB3.0+RJ45/SH")
			(pinfunction "MP")
			(pintype "bidirectional")
			(teardrops
				(best_length_ratio 0.4)
				(max_length 1)
				(best_width_ratio 0.9)
				(max_width 2)
				(curved_edges yes)
				(filter_ratio 0.9)
				(enabled yes)
				(allow_two_segments yes)
				(prefer_zone_connections yes)
			)
		)
		(pad "MP" thru_hole circle
			(at 4.88 15.09)
			(size 3 3)
			(drill 2.3)
			(layers "*.Cu" "*.Mask")
			(remove_unused_layers no)
			(net 579 "/2xUSB3.0+RJ45/SH")
			(pinfunction "MP")
			(pintype "bidirectional")
			(teardrops
				(best_length_ratio 0.4)
				(max_length 1)
				(best_width_ratio 0.9)
				(max_width 2)
				(curved_edges yes)
				(filter_ratio 0.9)
				(enabled yes)
				(allow_two_segments yes)
				(prefer_zone_connections yes)
			)
		)
		(pad "U1" thru_hole circle
			(at -7.945 11.4 270)
			(size 1.35 1.35)
			(drill 1)
			(layers "*.Cu" "*.Mask")
			(remove_unused_layers no)
			(net 42 "/2xUSB3.0+RJ45/P1_VBUS")
			(pinfunction "VBUS")
			(pintype "passive")
			(teardrops
				(best_length_ratio 0.4)
				(max_length 1)
				(best_width_ratio 0.9)
				(max_width 2)
				(curved_edges yes)
				(filter_ratio 0.9)
				(enabled yes)
				(allow_two_segments yes)
				(prefer_zone_connections yes)
			)
		)
		(pad "U2" thru_hole circle
			(at -5.445 11.4 270)
			(size 1.35 1.35)
			(drill 1)
			(layers "*.Cu" "*.Mask")
			(remove_unused_layers no)
			(net 123 "/2xUSB3.0+RJ45/P1_D-")
			(pinfunction "D-")
			(pintype "bidirectional")
			(teardrops
				(best_length_ratio 0.4)
				(max_length 1)
				(best_width_ratio 0.9)
				(max_width 2)
				(curved_edges yes)
				(filter_ratio 0.9)
				(enabled yes)
				(allow_two_segments yes)
				(prefer_zone_connections yes)
			)
		)
		(pad "U3" thru_hole circle
			(at -3.445 11.4 270)
			(size 1.35 1.35)
			(drill 1)
			(layers "*.Cu" "*.Mask")
			(remove_unused_layers no)
			(net 124 "/2xUSB3.0+RJ45/P1_D+")
			(pinfunction "D+")
			(pintype "bidirectional")
			(teardrops
				(best_length_ratio 0.4)
				(max_length 1)
				(best_width_ratio 0.9)
				(max_width 2)
				(curved_edges yes)
				(filter_ratio 0.9)
				(enabled yes)
				(allow_two_segments yes)
				(prefer_zone_connections yes)
			)
		)
		(pad "U4" thru_hole circle
			(at -0.945 11.4 270)
			(size 1.35 1.35)
			(drill 1)
			(layers "*.Cu" "*.Mask")
			(remove_unused_layers no)
			(net 1 "GND")
			(pinfunction "GND")
			(pintype "power_in")
			(teardrops
				(best_length_ratio 0.4)
				(max_length 1)
				(best_width_ratio 0.9)
				(max_width 2)
				(curved_edges yes)
				(filter_ratio 0.9)
				(enabled yes)
				(allow_two_segments yes)
				(prefer_zone_connections yes)
			)
		)
		(pad "U5" thru_hole circle
			(at -8.445 9.9 270)
			(size 1.35 1.35)
			(drill 1)
			(layers "*.Cu" "*.Mask")
			(remove_unused_layers no)
			(net 44 "/2xUSB3.0+RJ45/USBSS_1.TX+")
			(pinfunction "SSTX+")
			(pintype "bidirectional")
			(teardrops
				(best_length_ratio 0.4)
				(max_length 1)
				(best_width_ratio 0.9)
				(max_width 2)
				(curved_edges yes)
				(filter_ratio 0.9)
				(enabled yes)
				(allow_two_segments yes)
				(prefer_zone_connections yes)
			)
		)
		(pad "U6" thru_hole circle
			(at -6.445 9.9 270)
			(size 1.35 1.35)
			(drill 1)
			(layers "*.Cu" "*.Mask")
			(remove_unused_layers no)
			(net 47 "/2xUSB3.0+RJ45/USBSS_1.TX-")
			(pinfunction "SSTX-")
			(pintype "bidirectional")
			(teardrops
				(best_length_ratio 0.4)
				(max_length 1)
				(best_width_ratio 0.9)
				(max_width 2)
				(curved_edges yes)
				(filter_ratio 0.9)
				(enabled yes)
				(allow_two_segments yes)
				(prefer_zone_connections yes)
			)
		)
		(pad "U7" thru_hole circle
			(at -4.445 9.9 270)
			(size 1.35 1.35)
			(drill 1)
			(layers "*.Cu" "*.Mask")
			(remove_unused_layers no)
			(net 1 "GND")
			(pinfunction "GND_DRAIN")
			(pintype "power_in")
			(teardrops
				(best_length_ratio 0.4)
				(max_length 1)
				(best_width_ratio 0.9)
				(max_width 2)
				(curved_edges yes)
				(filter_ratio 0.9)
				(enabled yes)
				(allow_two_segments yes)
				(prefer_zone_connections yes)
			)
		)
		(pad "U8" thru_hole circle
			(at -2.445 9.9 270)
			(size 1.35 1.35)
			(drill 1)
			(layers "*.Cu" "*.Mask")
			(remove_unused_layers no)
			(net 159 "/2xUSB3.0+RJ45/USBSS_1.RX+")
			(pinfunction "SSRX+")
			(pintype "bidirectional")
			(teardrops
				(best_length_ratio 0.4)
				(max_length 1)
				(best_width_ratio 0.9)
				(max_width 2)
				(curved_edges yes)
				(filter_ratio 0.9)
				(enabled yes)
				(allow_two_segments yes)
				(prefer_zone_connections yes)
			)
		)
		(pad "U9" thru_hole circle
			(at -0.445 9.9 270)
			(size 1.35 1.35)
			(drill 1)
			(layers "*.Cu" "*.Mask")
			(remove_unused_layers no)
			(net 158 "/2xUSB3.0+RJ45/USBSS_1.RX-")
			(pinfunction "SSRX-")
			(pintype "bidirectional")
			(teardrops
				(best_length_ratio 0.4)
				(max_length 1)
				(best_width_ratio 0.9)
				(max_width 2)
				(curved_edges yes)
				(filter_ratio 0.9)
				(enabled yes)
				(allow_two_segments yes)
				(prefer_zone_connections yes)
			)
		)
		(pad "U10" thru_hole circle
			(at -7.945 8.2 270)
			(size 1.35 1.35)
			(drill 1)
			(layers "*.Cu" "*.Mask")
			(remove_unused_layers no)
			(net 43 "/2xUSB3.0+RJ45/P2_VBUS")
			(pinfunction "VBUS")
			(pintype "passive")
			(teardrops
				(best_length_ratio 0.4)
				(max_length 1)
				(best_width_ratio 0.9)
				(max_width 2)
				(curved_edges yes)
				(filter_ratio 0.9)
				(enabled yes)
				(allow_two_segments yes)
				(prefer_zone_connections yes)
			)
		)
		(pad "U11" thru_hole circle
			(at -5.445 8.2 270)
			(size 1.35 1.35)
			(drill 1)
			(layers "*.Cu" "*.Mask")
			(remove_unused_layers no)
			(net 125 "/2xUSB3.0+RJ45/P2_D-")
			(pinfunction "D-")
			(pintype "bidirectional")
			(teardrops
				(best_length_ratio 0.4)
				(max_length 1)
				(best_width_ratio 0.9)
				(max_width 2)
				(curved_edges yes)
				(filter_ratio 0.9)
				(enabled yes)
				(allow_two_segments yes)
				(prefer_zone_connections yes)
			)
		)
		(pad "U12" thru_hole circle
			(at -3.445 8.2 270)
			(size 1.35 1.35)
			(drill 1)
			(layers "*.Cu" "*.Mask")
			(remove_unused_layers no)
			(net 126 "/2xUSB3.0+RJ45/P2_D+")
			(pinfunction "D+")
			(pintype "bidirectional")
			(teardrops
				(best_length_ratio 0.4)
				(max_length 1)
				(best_width_ratio 0.9)
				(max_width 2)
				(curved_edges yes)
				(filter_ratio 0.9)
				(enabled yes)
				(allow_two_segments yes)
				(prefer_zone_connections yes)
			)
		)
		(pad "U13" thru_hole circle
			(at -0.945 8.2 270)
			(size 1.35 1.35)
			(drill 1)
			(layers "*.Cu" "*.Mask")
			(remove_unused_layers no)
			(net 1 "GND")
			(pinfunction "GND")
			(pintype "power_in")
			(teardrops
				(best_length_ratio 0.4)
				(max_length 1)
				(best_width_ratio 0.9)
				(max_width 2)
				(curved_edges yes)
				(filter_ratio 0.9)
				(enabled yes)
				(allow_two_segments yes)
				(prefer_zone_connections yes)
			)
		)
		(pad "U14" thru_hole circle
			(at -8.445 6.7 270)
			(size 1.35 1.35)
			(drill 1)
			(layers "*.Cu" "*.Mask")
			(remove_unused_layers no)
			(net 45 "/2xUSB3.0+RJ45/USBSS_2.TX+")
			(pinfunction "SSTX+")
			(pintype "bidirectional")
			(teardrops
				(best_length_ratio 0.4)
				(max_length 1)
				(best_width_ratio 0.9)
				(max_width 2)
				(curved_edges yes)
				(filter_ratio 0.9)
				(enabled yes)
				(allow_two_segments yes)
				(prefer_zone_connections yes)
			)
		)
		(pad "U15" thru_hole circle
			(at -6.445 6.7 270)
			(size 1.35 1.35)
			(drill 1)
			(layers "*.Cu" "*.Mask")
			(remove_unused_layers no)
			(net 49 "/2xUSB3.0+RJ45/USBSS_2.TX-")
			(pinfunction "SSTX-")
			(pintype "bidirectional")
			(teardrops
				(best_length_ratio 0.4)
				(max_length 1)
				(best_width_ratio 0.9)
				(max_width 2)
				(curved_edges yes)
				(filter_ratio 0.9)
				(enabled yes)
				(allow_two_segments yes)
				(prefer_zone_connections yes)
			)
		)
		(pad "U16" thru_hole circle
			(at -4.445 6.7 270)
			(size 1.35 1.35)
			(drill 1)
			(layers "*.Cu" "*.Mask")
			(remove_unused_layers no)
			(net 1 "GND")
			(pinfunction "GND_DRAIN")
			(pintype "power_in")
			(teardrops
				(best_length_ratio 0.4)
				(max_length 1)
				(best_width_ratio 0.9)
				(max_width 2)
				(curved_edges yes)
				(filter_ratio 0.9)
				(enabled yes)
				(allow_two_segments yes)
				(prefer_zone_connections yes)
			)
		)
		(pad "U17" thru_hole circle
			(at -2.445 6.7 270)
			(size 1.35 1.35)
			(drill 1)
			(layers "*.Cu" "*.Mask")
			(remove_unused_layers no)
			(net 161 "/2xUSB3.0+RJ45/USBSS_2.RX+")
			(pinfunction "SSRX+")
			(pintype "bidirectional")
			(teardrops
				(best_length_ratio 0.4)
				(max_length 1)
				(best_width_ratio 0.9)
				(max_width 2)
				(curved_edges yes)
				(filter_ratio 0.9)
				(enabled yes)
				(allow_two_segments yes)
				(prefer_zone_connections yes)
			)
		)
		(pad "U18" thru_hole circle
			(at -0.445 6.7 270)
			(size 1.35 1.35)
			(drill 1)
			(layers "*.Cu" "*.Mask")
			(remove_unused_layers no)
			(net 160 "/2xUSB3.0+RJ45/USBSS_2.RX-")
			(pinfunction "SSRX-")
			(pintype "bidirectional")
			(teardrops
				(best_length_ratio 0.4)
				(max_length 1)
				(best_width_ratio 0.9)
				(max_width 2)
				(curved_edges yes)
				(filter_ratio 0.9)
				(enabled yes)
				(allow_two_segments yes)
				(prefer_zone_connections yes)
			)
		)
	)
)
